(kicad_pcb
	(version 20260206)
	(generator "pcbnew")
	(generator_version "10.0")
	(general
		(thickness 1.6)
		(legacy_teardrops no)
	)
	(paper "A4")
	(title_block
		(title "01162023_DA0F0TEBIF0_F0T_Expander_BD_F_brd_V02_OCP.brd")
		(comment 1 "Grand Teton / footprints 7663-7671 of 9728")
	)
	(layers
		(0 "F.Cu" signal "TOP")
		(4 "In1.Cu" signal "GND")
		(6 "In2.Cu" signal "VCC")
		(8 "In3.Cu" signal "VCC1")
		(10 "In4.Cu" signal "GND1")
		(12 "In5.Cu" signal "IN1")
		(14 "In6.Cu" signal "GND2")
		(16 "In7.Cu" signal "IN2")
		(18 "In8.Cu" signal "GND3")
		(20 "In9.Cu" signal "IN3")
		(22 "In10.Cu" signal "GND4")
		(24 "In11.Cu" signal "IN4")
		(26 "In12.Cu" signal "GND5")
		(28 "In13.Cu" signal "IN5")
		(30 "In14.Cu" signal "GND6")
		(32 "In15.Cu" signal "IN6")
		(34 "In16.Cu" signal "GND7")
		(2 "B.Cu" signal "BOTTOM")
		(9 "F.Adhes" user "F.Adhesive")
		(11 "B.Adhes" user "B.Adhesive")
		(13 "F.Paste" user "Package Geometry/Pastemask Top")
		(15 "B.Paste" user "Package Geometry/Pastemask Bottom")
		(5 "F.SilkS" user "Ref Des/Silkscreen Top")
		(7 "B.SilkS" user "Ref Des/Silkscreen Bottom")
		(1 "F.Mask" user "Board Geometry/Soldermask Top")
		(3 "B.Mask" user "Board Geometry/Soldermask Bottom")
		(17 "Dwgs.User" user "User.Drawings")
		(19 "Cmts.User" user "User.Comments")
		(21 "Eco1.User" user "User.Eco1")
		(23 "Eco2.User" user "User.Eco2")
		(25 "Edge.Cuts" user "Board Geometry/Outline")
		(27 "Margin" user)
		(31 "F.CrtYd" user "Package Geometry/Place Bound Top")
		(29 "B.CrtYd" user "Package Geometry/Place Bound Bottom")
		(35 "F.Fab" user "Ref Des/Assembly Top")
		(33 "B.Fab" user "Ref Des/Assembly Bottom")
	)
	(footprint ""
		(layer "B.Cu")
		(at 212.507576 -218.316048 -90)
		(property "Reference" "R4879"
			(at 0 0 90)
			(layer "B.SilkS")
			(hide yes)
			(effects
				(font
					(size 1.27 1.27)
				)
				(justify mirror)
			)
		)
		(property "Value" ""
			(at 0 0 90)
			(layer "B.Fab")
			(effects
				(font
					(size 1.27 1.27)
				)
				(justify mirror)
			)
		)
		(duplicate_pad_numbers_are_jumpers no)
		(fp_line
			(start -0.7874 0.4064)
			(end 0.7874 0.4064)
			(stroke
				(width 0.1524)
				(type default)
			)
			(layer "B.SilkS")
		)
		(fp_line
			(start 0.7874 0.4064)
			(end 0.7874 -0.4064)
			(stroke
				(width 0.1524)
				(type default)
			)
			(layer "B.SilkS")
		)
		(fp_line
			(start -0.7874 -0.4064)
			(end -0.7874 0.4064)
			(stroke
				(width 0.1524)
				(type default)
			)
			(layer "B.SilkS")
		)
		(fp_line
			(start 0.7874 -0.4064)
			(end -0.7874 -0.4064)
			(stroke
				(width 0.1524)
				(type default)
			)
			(layer "B.SilkS")
		)
		(fp_line
			(start -0.67945 0.3048)
			(end -0.120396 0.3048)
			(stroke
				(width 0.1)
				(type default)
			)
			(layer "B.Fab")
		)
		(fp_line
			(start -0.120396 0.3048)
			(end -0.120396 0.2794)
			(stroke
				(width 0.1)
				(type default)
			)
			(layer "B.Fab")
		)
		(fp_line
			(start 0.12065 0.3048)
			(end 0.67945 0.3048)
			(stroke
				(width 0.1)
				(type default)
			)
			(layer "B.Fab")
		)
		(fp_line
			(start 0.67945 0.3048)
			(end 0.67945 -0.305054)
			(stroke
				(width 0.1)
				(type default)
			)
			(layer "B.Fab")
		)
		(fp_line
			(start -0.120396 0.2794)
			(end 0.12065 0.2794)
			(stroke
				(width 0.1)
				(type default)
			)
			(layer "B.Fab")
		)
		(fp_line
			(start 0.12065 0.2794)
			(end 0.12065 0.3048)
			(stroke
				(width 0.1)
				(type default)
			)
			(layer "B.Fab")
		)
		(fp_line
			(start -0.12065 -0.2794)
			(end -0.12065 -0.3048)
			(stroke
				(width 0.1)
				(type default)
			)
			(layer "B.Fab")
		)
		(fp_line
			(start 0.12065 -0.2794)
			(end -0.12065 -0.2794)
			(stroke
				(width 0.1)
				(type default)
			)
			(layer "B.Fab")
		)
		(fp_line
			(start -0.67945 -0.3048)
			(end -0.67945 0.3048)
			(stroke
				(width 0.1)
				(type default)
			)
			(layer "B.Fab")
		)
		(fp_line
			(start -0.12065 -0.3048)
			(end -0.67945 -0.3048)
			(stroke
				(width 0.1)
				(type default)
			)
			(layer "B.Fab")
		)
		(fp_line
			(start 0.12065 -0.305054)
			(end 0.12065 -0.2794)
			(stroke
				(width 0.1)
				(type default)
			)
			(layer "B.Fab")
		)
		(fp_line
			(start 0.67945 -0.305054)
			(end 0.12065 -0.305054)
			(stroke
				(width 0.1)
				(type default)
			)
			(layer "B.Fab")
		)
		(pad "1" smd circle
			(at 0.40005 0 90)
			(size 0 0)
			(layers "B.Cu" "B.Mask" "B.Paste")
			(net "P1V2_AUX")
		)
		(pad "2" smd circle
			(at -0.40005 0 90)
			(size 0 0)
			(layers "B.Cu" "B.Mask" "B.Paste")
			(net "SMB_NIC7_SCL")
		)
	)
	(footprint ""
		(layer "B.Cu")
		(at 293.921942 -197.499732 -90)
		(property "Reference" "U64"
			(at 1.5367 -2.25933 270)
			(unlocked yes)
			(layer "B.SilkS")
			(effects
				(font
					(size 0.7874 0.5842)
					(thickness 0.1524)
				)
				(justify mirror)
			)
		)
		(property "Value" ""
			(at 0 0 90)
			(layer "B.Fab")
			(effects
				(font
					(size 1.27 1.27)
				)
				(justify mirror)
			)
		)
		(duplicate_pad_numbers_are_jumpers no)
		(fp_line
			(start -2.036064 1.525016)
			(end 2.038096 1.525016)
			(stroke
				(width 0.1524)
				(type default)
			)
			(layer "B.SilkS")
		)
		(fp_line
			(start 2.038096 1.525016)
			(end 2.038096 -1.525016)
			(stroke
				(width 0.1524)
				(type default)
			)
			(layer "B.SilkS")
		)
		(fp_line
			(start 0 -0.6604)
			(end -0.4572 -1.4986)
			(stroke
				(width 0.1524)
				(type default)
			)
			(layer "B.SilkS")
		)
		(fp_line
			(start 0.508 -1.524)
			(end 0 -0.6604)
			(stroke
				(width 0.1524)
				(type default)
			)
			(layer "B.SilkS")
		)
		(fp_line
			(start -2.036064 -1.525016)
			(end -2.036064 1.525016)
			(stroke
				(width 0.1524)
				(type default)
			)
			(layer "B.SilkS")
		)
		(fp_line
			(start 2.038096 -1.525016)
			(end -2.036064 -1.525016)
			(stroke
				(width 0.1524)
				(type default)
			)
			(layer "B.SilkS")
		)
		(fp_poly
			(pts
				(xy 2.71272 -0.592328) (xy 2.71272 -1.217168) (xy 2.159 -0.889)
			)
			(stroke
				(width 0)
				(type default)
			)
			(fill yes)
			(layer "B.SilkS")
		)
		(fp_line
			(start -0.87503 1.525016)
			(end 0.87503 1.525016)
			(stroke
				(width 0.1)
				(type default)
			)
			(layer "B.Fab")
		)
		(fp_line
			(start 0.87503 1.525016)
			(end 0.87503 -1.525016)
			(stroke
				(width 0.1)
				(type default)
			)
			(layer "B.Fab")
		)
		(fp_line
			(start -0.87503 -1.525016)
			(end -0.87503 1.525016)
			(stroke
				(width 0.1)
				(type default)
			)
			(layer "B.Fab")
		)
		(fp_line
			(start 0.87503 -1.525016)
			(end -0.87503 -1.525016)
			(stroke
				(width 0.1)
				(type default)
			)
			(layer "B.Fab")
		)
		(fp_poly
			(pts
				(xy 2.71272 -0.592328) (xy 2.71272 -1.217168) (xy 2.159 -0.889)
			)
			(stroke
				(width 0)
				(type default)
			)
			(fill yes)
			(layer "B.Fab")
		)
		(pad "1" smd rect
			(at 1.35001 -0.94996 180)
			(size 0.6096 1.0668)
			(layers "B.Cu" "B.Mask" "B.Paste")
			(net "SEL_FLASH_PEX2_BUF_R")
		)
		(pad "2" smd rect
			(at 1.35001 0 180)
			(size 0.6096 1.0668)
			(layers "B.Cu" "B.Mask" "B.Paste")
			(net "SEL_FLASH_PEX3_BUF_R")
		)
		(pad "3" smd rect
			(at 1.35001 0.94996 180)
			(size 0.6096 1.0668)
			(layers "B.Cu" "B.Mask" "B.Paste")
			(net "GND")
		)
		(pad "4" smd rect
			(at -1.35001 0.94996 180)
			(size 0.6096 1.0668)
			(layers "B.Cu" "B.Mask" "B.Paste")
			(net "SPI_BIC1_LS23_EN")
		)
		(pad "5" smd rect
			(at -1.35001 -0.94996 180)
			(size 0.6096 1.0668)
			(layers "B.Cu" "B.Mask" "B.Paste")
			(net "P3V3_AUX")
		)
	)
	(footprint ""
		(layer "B.Cu")
		(at 77.541882 -98.021648 180)
		(property "Reference" "R64"
			(at 0 0 0)
			(layer "B.SilkS")
			(hide yes)
			(effects
				(font
					(size 1.27 1.27)
				)
				(justify mirror)
			)
		)
		(property "Value" ""
			(at 0 0 0)
			(layer "B.Fab")
			(effects
				(font
					(size 1.27 1.27)
				)
				(justify mirror)
			)
		)
		(duplicate_pad_numbers_are_jumpers no)
		(fp_line
			(start 0.7874 0.4064)
			(end 0.7874 -0.4064)
			(stroke
				(width 0.1524)
				(type default)
			)
			(layer "B.SilkS")
		)
		(fp_line
			(start 0.7874 -0.4064)
			(end -0.7874 -0.4064)
			(stroke
				(width 0.1524)
				(type default)
			)
			(layer "B.SilkS")
		)
		(fp_line
			(start -0.7874 0.4064)
			(end 0.7874 0.4064)
			(stroke
				(width 0.1524)
				(type default)
			)
			(layer "B.SilkS")
		)
		(fp_line
			(start -0.7874 -0.4064)
			(end -0.7874 0.4064)
			(stroke
				(width 0.1524)
				(type default)
			)
			(layer "B.SilkS")
		)
		(fp_line
			(start 0.67945 0.3048)
			(end 0.67945 -0.305054)
			(stroke
				(width 0.1)
				(type default)
			)
			(layer "B.Fab")
		)
		(fp_line
			(start 0.67945 -0.305054)
			(end 0.12065 -0.305054)
			(stroke
				(width 0.1)
				(type default)
			)
			(layer "B.Fab")
		)
		(fp_line
			(start 0.12065 0.3048)
			(end 0.67945 0.3048)
			(stroke
				(width 0.1)
				(type default)
			)
			(layer "B.Fab")
		)
		(fp_line
			(start 0.12065 0.2794)
			(end 0.12065 0.3048)
			(stroke
				(width 0.1)
				(type default)
			)
			(layer "B.Fab")
		)
		(fp_line
			(start 0.12065 -0.2794)
			(end -0.12065 -0.2794)
			(stroke
				(width 0.1)
				(type default)
			)
			(layer "B.Fab")
		)
		(fp_line
			(start 0.12065 -0.305054)
			(end 0.12065 -0.2794)
			(stroke
				(width 0.1)
				(type default)
			)
			(layer "B.Fab")
		)
		(fp_line
			(start -0.120396 0.3048)
			(end -0.120396 0.2794)
			(stroke
				(width 0.1)
				(type default)
			)
			(layer "B.Fab")
		)
		(fp_line
			(start -0.120396 0.2794)
			(end 0.12065 0.2794)
			(stroke
				(width 0.1)
				(type default)
			)
			(layer "B.Fab")
		)
		(fp_line
			(start -0.12065 -0.2794)
			(end -0.12065 -0.3048)
			(stroke
				(width 0.1)
				(type default)
			)
			(layer "B.Fab")
		)
		(fp_line
			(start -0.12065 -0.3048)
			(end -0.67945 -0.3048)
			(stroke
				(width 0.1)
				(type default)
			)
			(layer "B.Fab")
		)
		(fp_line
			(start -0.67945 0.3048)
			(end -0.120396 0.3048)
			(stroke
				(width 0.1)
				(type default)
			)
			(layer "B.Fab")
		)
		(fp_line
			(start -0.67945 -0.3048)
			(end -0.67945 0.3048)
			(stroke
				(width 0.1)
				(type default)
			)
			(layer "B.Fab")
		)
		(pad "1" smd circle
			(at 0.40005 0)
			(size 0 0)
			(layers "B.Cu" "B.Mask" "B.Paste")
			(net "NIC1_DATA_OUT")
		)
		(pad "2" smd circle
			(at -0.40005 0)
			(size 0 0)
			(layers "B.Cu" "B.Mask" "B.Paste")
			(net "GND")
		)
	)
	(footprint ""
		(layer "B.Cu")
		(at 405.100028 -303.499774 -90)
		(property "Reference" "C3435"
			(at 0 0 90)
			(layer "B.SilkS")
			(hide yes)
			(effects
				(font
					(size 1.27 1.27)
				)
				(justify mirror)
			)
		)
		(property "Value" ""
			(at 0 0 90)
			(layer "B.Fab")
			(effects
				(font
					(size 1.27 1.27)
				)
				(justify mirror)
			)
		)
		(duplicate_pad_numbers_are_jumpers no)
		(fp_line
			(start -0.299974 0.150114)
			(end 0.299974 0.150114)
			(stroke
				(width 0.1)
				(type default)
			)
			(layer "B.Fab")
		)
		(fp_line
			(start 0.299974 0.150114)
			(end 0.299974 -0.150114)
			(stroke
				(width 0.1)
				(type default)
			)
			(layer "B.Fab")
		)
		(fp_line
			(start -0.299974 -0.150114)
			(end -0.299974 0.150114)
			(stroke
				(width 0.1)
				(type default)
			)
			(layer "B.Fab")
		)
		(fp_line
			(start 0.299974 -0.150114)
			(end -0.299974 -0.150114)
			(stroke
				(width 0.1)
				(type default)
			)
			(layer "B.Fab")
		)
		(pad "1" smd rect
			(at 0.2667 0 90)
			(size 0.3048 0.381)
			(layers "B.Cu" "B.Mask" "B.Paste")
			(net "P1V25_PEX3")
		)
		(pad "2" smd rect
			(at -0.2667 0 90)
			(size 0.3048 0.381)
			(layers "B.Cu" "B.Mask" "B.Paste")
			(net "GND")
		)
	)
	(footprint ""
		(layer "B.Cu")
		(at 394.65504 -299.212)
		(property "Reference" "C3548"
			(at 0 0 0)
			(layer "B.SilkS")
			(hide yes)
			(effects
				(font
					(size 1.27 1.27)
				)
				(justify mirror)
			)
		)
		(property "Value" ""
			(at 0 0 0)
			(layer "B.Fab")
			(effects
				(font
					(size 1.27 1.27)
				)
				(justify mirror)
			)
		)
		(duplicate_pad_numbers_are_jumpers no)
		(fp_line
			(start -0.299974 -0.150114)
			(end -0.299974 0.150114)
			(stroke
				(width 0.1)
				(type default)
			)
			(layer "B.Fab")
		)
		(fp_line
			(start -0.299974 0.150114)
			(end 0.299974 0.150114)
			(stroke
				(width 0.1)
				(type default)
			)
			(layer "B.Fab")
		)
		(fp_line
			(start 0.299974 -0.150114)
			(end -0.299974 -0.150114)
			(stroke
				(width 0.1)
				(type default)
			)
			(layer "B.Fab")
		)
		(fp_line
			(start 0.299974 0.150114)
			(end 0.299974 -0.150114)
			(stroke
				(width 0.1)
				(type default)
			)
			(layer "B.Fab")
		)
		(pad "1" smd rect
			(at 0.2667 0 180)
			(size 0.3048 0.381)
			(layers "B.Cu" "B.Mask" "B.Paste")
			(net "PCEPLL1_VDDA18_PEX3")
		)
		(pad "2" smd rect
			(at -0.2667 0 180)
			(size 0.3048 0.381)
			(layers "B.Cu" "B.Mask" "B.Paste")
			(net "GND")
		)
	)
	(footprint ""
		(layer "B.Cu")
		(at 52.999894 -299.699934 -90)
		(property "Reference" "C1190"
			(at 0 0 90)
			(layer "B.SilkS")
			(hide yes)
			(effects
				(font
					(size 1.27 1.27)
				)
				(justify mirror)
			)
		)
		(property "Value" ""
			(at 0 0 90)
			(layer "B.Fab")
			(effects
				(font
					(size 1.27 1.27)
				)
				(justify mirror)
			)
		)
		(duplicate_pad_numbers_are_jumpers no)
		(fp_line
			(start -0.299974 0.150114)
			(end 0.299974 0.150114)
			(stroke
				(width 0.1)
				(type default)
			)
			(layer "B.Fab")
		)
		(fp_line
			(start 0.299974 0.150114)
			(end 0.299974 -0.150114)
			(stroke
				(width 0.1)
				(type default)
			)
			(layer "B.Fab")
		)
		(fp_line
			(start -0.299974 -0.150114)
			(end -0.299974 0.150114)
			(stroke
				(width 0.1)
				(type default)
			)
			(layer "B.Fab")
		)
		(fp_line
			(start 0.299974 -0.150114)
			(end -0.299974 -0.150114)
			(stroke
				(width 0.1)
				(type default)
			)
			(layer "B.Fab")
		)
		(pad "1" smd rect
			(at 0.2667 0 90)
			(size 0.3048 0.381)
			(layers "B.Cu" "B.Mask" "B.Paste")
			(net "P0V8_SERDES_VDDA_PEX0")
		)
		(pad "2" smd rect
			(at -0.2667 0 90)
			(size 0.3048 0.381)
			(layers "B.Cu" "B.Mask" "B.Paste")
			(net "GND")
		)
	)
	(footprint ""
		(layer "B.Cu")
		(at 230.416354 -150.431246 90)
		(property "Reference" "C2788"
			(at 0 0 90)
			(layer "B.SilkS")
			(hide yes)
			(effects
				(font
					(size 1.27 1.27)
				)
				(justify mirror)
			)
		)
		(property "Value" ""
			(at 0 0 90)
			(layer "B.Fab")
			(effects
				(font
					(size 1.27 1.27)
				)
				(justify mirror)
			)
		)
		(duplicate_pad_numbers_are_jumpers no)
		(fp_line
			(start 0.7874 -0.4064)
			(end -0.7874 -0.4064)
			(stroke
				(width 0.1524)
				(type default)
			)
			(layer "B.SilkS")
		)
		(fp_line
			(start -0.7874 -0.4064)
			(end -0.7874 0.4064)
			(stroke
				(width 0.1524)
				(type default)
			)
			(layer "B.SilkS")
		)
		(fp_line
			(start 0.7874 0.4064)
			(end 0.7874 -0.4064)
			(stroke
				(width 0.1524)
				(type default)
			)
			(layer "B.SilkS")
		)
		(fp_line
			(start -0.7874 0.4064)
			(end 0.7874 0.4064)
			(stroke
				(width 0.1524)
				(type default)
			)
			(layer "B.SilkS")
		)
		(fp_line
			(start 0.67945 -0.305054)
			(end 0.12065 -0.305054)
			(stroke
				(width 0.1)
				(type default)
			)
			(layer "B.Fab")
		)
		(fp_line
			(start 0.12065 -0.305054)
			(end 0.12065 -0.2794)
			(stroke
				(width 0.1)
				(type default)
			)
			(layer "B.Fab")
		)
		(fp_line
			(start -0.12065 -0.3048)
			(end -0.67945 -0.3048)
			(stroke
				(width 0.1)
				(type default)
			)
			(layer "B.Fab")
		)
		(fp_line
			(start -0.67945 -0.3048)
			(end -0.67945 0.3048)
			(stroke
				(width 0.1)
				(type default)
			)
			(layer "B.Fab")
		)
		(fp_line
			(start 0.12065 -0.2794)
			(end -0.12065 -0.2794)
			(stroke
				(width 0.1)
				(type default)
			)
			(layer "B.Fab")
		)
		(fp_line
			(start -0.12065 -0.2794)
			(end -0.12065 -0.3048)
			(stroke
				(width 0.1)
				(type default)
			)
			(layer "B.Fab")
		)
		(fp_line
			(start 0.12065 0.2794)
			(end 0.12065 0.3048)
			(stroke
				(width 0.1)
				(type default)
			)
			(layer "B.Fab")
		)
		(fp_line
			(start -0.120396 0.2794)
			(end 0.12065 0.2794)
			(stroke
				(width 0.1)
				(type default)
			)
			(layer "B.Fab")
		)
		(fp_line
			(start 0.67945 0.3048)
			(end 0.67945 -0.305054)
			(stroke
				(width 0.1)
				(type default)
			)
			(layer "B.Fab")
		)
		(fp_line
			(start 0.12065 0.3048)
			(end 0.67945 0.3048)
			(stroke
				(width 0.1)
				(type default)
			)
			(layer "B.Fab")
		)
		(fp_line
			(start -0.120396 0.3048)
			(end -0.120396 0.2794)
			(stroke
				(width 0.1)
				(type default)
			)
			(layer "B.Fab")
		)
		(fp_line
			(start -0.67945 0.3048)
			(end -0.120396 0.3048)
			(stroke
				(width 0.1)
				(type default)
			)
			(layer "B.Fab")
		)
		(pad "1" smd circle
			(at 0.40005 0 270)
			(size 0 0)
			(layers "B.Cu" "B.Mask" "B.Paste")
			(net "P3V3_CLK_GEN_VDD_CK440_PEX")
		)
		(pad "2" smd circle
			(at -0.40005 0 270)
			(size 0 0)
			(layers "B.Cu" "B.Mask" "B.Paste")
			(net "GND")
		)
	)
	(footprint ""
		(layer "B.Cu")
		(at 64.399922 -290.199826 90)
		(property "Reference" "C1236"
			(at 0 0 90)
			(layer "B.SilkS")
			(hide yes)
			(effects
				(font
					(size 1.27 1.27)
				)
				(justify mirror)
			)
		)
		(property "Value" ""
			(at 0 0 90)
			(layer "B.Fab")
			(effects
				(font
					(size 1.27 1.27)
				)
				(justify mirror)
			)
		)
		(duplicate_pad_numbers_are_jumpers no)
		(fp_line
			(start 0.299974 -0.150114)
			(end -0.299974 -0.150114)
			(stroke
				(width 0.1)
				(type default)
			)
			(layer "B.Fab")
		)
		(fp_line
			(start -0.299974 -0.150114)
			(end -0.299974 0.150114)
			(stroke
				(width 0.1)
				(type default)
			)
			(layer "B.Fab")
		)
		(fp_line
			(start 0.299974 0.150114)
			(end 0.299974 -0.150114)
			(stroke
				(width 0.1)
				(type default)
			)
			(layer "B.Fab")
		)
		(fp_line
			(start -0.299974 0.150114)
			(end 0.299974 0.150114)
			(stroke
				(width 0.1)
				(type default)
			)
			(layer "B.Fab")
		)
		(pad "1" smd rect
			(at 0.2667 0 270)
			(size 0.3048 0.381)
			(layers "B.Cu" "B.Mask" "B.Paste")
			(net "P0V8_SERDES_VDDA_PEX0")
		)
		(pad "2" smd rect
			(at -0.2667 0 270)
			(size 0.3048 0.381)
			(layers "B.Cu" "B.Mask" "B.Paste")
			(net "GND")
		)
	)
	(footprint ""
		(layer "B.Cu")
		(at 297.549824 -299.699934 -90)
		(property "Reference" "C1693"
			(at 0 0 90)
			(layer "B.SilkS")
			(hide yes)
			(effects
				(font
					(size 1.27 1.27)
				)
				(justify mirror)
			)
		)
		(property "Value" ""
			(at 0 0 90)
			(layer "B.Fab")
			(effects
				(font
					(size 1.27 1.27)
				)
				(justify mirror)
			)
		)
		(duplicate_pad_numbers_are_jumpers no)
		(fp_line
			(start -0.299974 0.150114)
			(end 0.299974 0.150114)
			(stroke
				(width 0.1)
				(type default)
			)
			(layer "B.Fab")
		)
		(fp_line
			(start 0.299974 0.150114)
			(end 0.299974 -0.150114)
			(stroke
				(width 0.1)
				(type default)
			)
			(layer "B.Fab")
		)
		(fp_line
			(start -0.299974 -0.150114)
			(end -0.299974 0.150114)
			(stroke
				(width 0.1)
				(type default)
			)
			(layer "B.Fab")
		)
		(fp_line
			(start 0.299974 -0.150114)
			(end -0.299974 -0.150114)
			(stroke
				(width 0.1)
				(type default)
			)
			(layer "B.Fab")
		)
		(pad "1" smd rect
			(at 0.2667 0 90)
			(size 0.3048 0.381)
			(layers "B.Cu" "B.Mask" "B.Paste")
			(net "P0V8_SERDES_VDDA_PEX2")
		)
		(pad "2" smd rect
			(at -0.2667 0 90)
			(size 0.3048 0.381)
			(layers "B.Cu" "B.Mask" "B.Paste")
			(net "GND")
		)
	)
)
